# S9S_MB_2U (Grand Teton) — schematic netlist excerpt (pin names and nets, part order shuffled) for the footprints in the layout excerpt that follows; sources: Cadence DE-HDL packaged netlist, KiCad conversion of 03242023_DA0F0TMBIJ0_F0T_Motherboard_J_brd_V01_OCP.brd

C260  Q_CAP  47UF 4V 20% X6S  pkg C0805  page 77 : A = PVCCIN_CPU1 ; B = GND
R380  Q_RES  1K 1% EMPTY  pkg 0402LF  page 198 : A = P3V3_AUX ; B = FM_FLASH_SECURITY_STRAP

Y3  Q_XTAL_4P_13BI_24GND  25MHZ MISC  pkg X_4S_FL4000120_3-2X2-5  page 212
  X1  = CLK_GEN2_XTAL_IN_R
  G1  = GND
  X2  = CLK_GEN2_XTAL_OUT
  G2  = GND

(kicad_pcb
	(version 20260206)
	(generator "pcbnew")
	(generator_version "10.0")
	(general
		(thickness 1.6)
		(legacy_teardrops no)
	)
	(paper "A4")
	(title_block
		(title "03242023_DA0F0TMBIJ0_F0T_Motherboard_J_brd_V01_OCP.brd")
		(comment 1 "Grand Teton / footprints 2396-2398 of 6105")
	)
	(layers
		(0 "F.Cu" signal "TOP")
		(4 "In1.Cu" signal "GND")
		(6 "In2.Cu" signal "IN1")
		(8 "In3.Cu" signal "GND1")
		(10 "In4.Cu" signal "IN2")
		(12 "In5.Cu" signal "GND2")
		(14 "In6.Cu" signal "IN3")
		(16 "In7.Cu" signal "GND3")
		(18 "In8.Cu" signal "VCC")
		(20 "In9.Cu" signal "VCC1")
		(22 "In10.Cu" signal "GND4")
		(24 "In11.Cu" signal "IN4")
		(26 "In12.Cu" signal "GND5")
		(28 "In13.Cu" signal "IN5")
		(30 "In14.Cu" signal "GND6")
		(32 "In15.Cu" signal "IN6")
		(34 "In16.Cu" signal "GND7")
		(2 "B.Cu" signal "BOTTOM")
		(9 "F.Adhes" user "F.Adhesive")
		(11 "B.Adhes" user "B.Adhesive")
		(13 "F.Paste" user "Package Geometry/Pastemask Top")
		(15 "B.Paste" user "Package Geometry/Pastemask Bottom")
		(5 "F.SilkS" user "Ref Des/Silkscreen Top")
		(7 "B.SilkS" user "Ref Des/Silkscreen Bottom")
		(1 "F.Mask" user "Board Geometry/Soldermask Top")
		(3 "B.Mask" user "Board Geometry/Soldermask Bottom")
		(17 "Dwgs.User" user "User.Drawings")
		(19 "Cmts.User" user "User.Comments")
		(21 "Eco1.User" user "User.Eco1")
		(23 "Eco2.User" user "User.Eco2")
		(25 "Edge.Cuts" user "Board Geometry/Outline")
		(27 "Margin" user)
		(31 "F.CrtYd" user "Package Geometry/Place Bound Top")
		(29 "B.CrtYd" user "Package Geometry/Place Bound Bottom")
		(35 "F.Fab" user "Ref Des/Assembly Top")
		(33 "B.Fab" user "Ref Des/Assembly Bottom")
	)
	(footprint ""
		(layer "F.Cu")
		(at 242.92179 -249.281442 180)
		(property "Reference" "Y3"
			(at -0.22225 -3.369564 0)
			(unlocked yes)
			(layer "F.SilkS")
			(effects
				(font
					(size 0.7874 0.5842)
					(thickness 0.1524)
				)
				(justify left)
			)
		)
		(property "Value" ""
			(at 0 0 180)
			(layer "F.Fab")
			(effects
				(font
					(size 1.27 1.27)
				)
			)
		)
		(duplicate_pad_numbers_are_jumpers no)
		(fp_line
			(start 1.538732 1.937004)
			(end -1.538732 1.937004)
			(stroke
				(width 0.1524)
				(type default)
			)
			(layer "F.SilkS")
		)
		(fp_line
			(start 1.538732 -1.937004)
			(end 1.538732 1.937004)
			(stroke
				(width 0.1524)
				(type default)
			)
			(layer "F.SilkS")
		)
		(fp_line
			(start -1.538732 1.937004)
			(end -1.538732 -1.937004)
			(stroke
				(width 0.1524)
				(type default)
			)
			(layer "F.SilkS")
		)
		(fp_line
			(start -1.538732 -1.937004)
			(end 1.538732 -1.937004)
			(stroke
				(width 0.1524)
				(type default)
			)
			(layer "F.SilkS")
		)
		(fp_poly
			(pts
				(xy -1.724406 -1.059942) (xy -2.5908 -0.626872) (xy -2.5908 -1.493266)
			)
			(stroke
				(width 0)
				(type default)
			)
			(fill yes)
			(layer "F.SilkS")
		)
		(fp_line
			(start 1.299972 1.649984)
			(end -1.299972 1.649984)
			(stroke
				(width 0.1)
				(type default)
			)
			(layer "F.Fab")
		)
		(fp_line
			(start 1.299972 -1.649984)
			(end 1.299972 1.649984)
			(stroke
				(width 0.1)
				(type default)
			)
			(layer "F.Fab")
		)
		(fp_line
			(start -1.299972 1.649984)
			(end -1.299972 -1.649984)
			(stroke
				(width 0.1)
				(type default)
			)
			(layer "F.Fab")
		)
		(fp_line
			(start -1.299972 -1.649984)
			(end 1.299972 -1.649984)
			(stroke
				(width 0.1)
				(type default)
			)
			(layer "F.Fab")
		)
		(fp_poly
			(pts
				(xy -2.5908 -0.626872) (xy -2.5908 -1.493266) (xy -1.724406 -1.059942)
			)
			(stroke
				(width 0)
				(type default)
			)
			(fill yes)
			(layer "F.Fab")
		)
		(pad "1" smd rect
			(at -0.8001 -1.059942 180)
			(size 1.2192 1.4986)
			(layers "F.Cu" "F.Mask" "F.Paste")
			(net "CLK_GEN2_XTAL_IN_R")
		)
		(pad "2" smd rect
			(at -0.8001 1.059942 180)
			(size 1.2192 1.4986)
			(layers "F.Cu" "F.Mask" "F.Paste")
			(net "GND")
		)
		(pad "3" smd rect
			(at 0.8001 1.059942 180)
			(size 1.2192 1.4986)
			(layers "F.Cu" "F.Mask" "F.Paste")
			(net "CLK_GEN2_XTAL_OUT")
		)
		(pad "4" smd rect
			(at 0.8001 -1.059942 180)
			(size 1.2192 1.4986)
			(layers "F.Cu" "F.Mask" "F.Paste")
			(net "GND")
		)
	)
	(footprint ""
		(layer "F.Cu")
		(at 312.443622 -42.713148)
		(property "Reference" "R380"
			(at 0 0 0)
			(layer "F.SilkS")
			(hide yes)
			(effects
				(font
					(size 1.27 1.27)
				)
			)
		)
		(property "Value" ""
			(at 0 0 0)
			(layer "F.Fab")
			(effects
				(font
					(size 1.27 1.27)
				)
			)
		)
		(duplicate_pad_numbers_are_jumpers no)
		(fp_line
			(start -0.7874 -0.4064)
			(end 0.7874 -0.4064)
			(stroke
				(width 0.1524)
				(type default)
			)
			(layer "F.SilkS")
		)
		(fp_line
			(start -0.7874 0.4064)
			(end -0.7874 -0.4064)
			(stroke
				(width 0.1524)
				(type default)
			)
			(layer "F.SilkS")
		)
		(fp_line
			(start 0.7874 -0.4064)
			(end 0.7874 0.4064)
			(stroke
				(width 0.1524)
				(type default)
			)
			(layer "F.SilkS")
		)
		(fp_line
			(start 0.7874 0.4064)
			(end -0.7874 0.4064)
			(stroke
				(width 0.1524)
				(type default)
			)
			(layer "F.SilkS")
		)
		(fp_line
			(start -0.67945 -0.305054)
			(end -0.12065 -0.305054)
			(stroke
				(width 0.1)
				(type default)
			)
			(layer "F.Fab")
		)
		(fp_line
			(start -0.67945 0.3048)
			(end -0.67945 -0.305054)
			(stroke
				(width 0.1)
				(type default)
			)
			(layer "F.Fab")
		)
		(fp_line
			(start -0.12065 -0.305054)
			(end -0.12065 -0.2794)
			(stroke
				(width 0.1)
				(type default)
			)
			(layer "F.Fab")
		)
		(fp_line
			(start -0.12065 -0.2794)
			(end 0.12065 -0.2794)
			(stroke
				(width 0.1)
				(type default)
			)
			(layer "F.Fab")
		)
		(fp_line
			(start -0.12065 0.2794)
			(end -0.12065 0.3048)
			(stroke
				(width 0.1)
				(type default)
			)
			(layer "F.Fab")
		)
		(fp_line
			(start -0.12065 0.3048)
			(end -0.67945 0.3048)
			(stroke
				(width 0.1)
				(type default)
			)
			(layer "F.Fab")
		)
		(fp_line
			(start 0.120396 0.2794)
			(end -0.12065 0.2794)
			(stroke
				(width 0.1)
				(type default)
			)
			(layer "F.Fab")
		)
		(fp_line
			(start 0.120396 0.3048)
			(end 0.120396 0.2794)
			(stroke
				(width 0.1)
				(type default)
			)
			(layer "F.Fab")
		)
		(fp_line
			(start 0.12065 -0.3048)
			(end 0.67945 -0.3048)
			(stroke
				(width 0.1)
				(type default)
			)
			(layer "F.Fab")
		)
		(fp_line
			(start 0.12065 -0.2794)
			(end 0.12065 -0.3048)
			(stroke
				(width 0.1)
				(type default)
			)
			(layer "F.Fab")
		)
		(fp_line
			(start 0.67945 -0.3048)
			(end 0.67945 0.3048)
			(stroke
				(width 0.1)
				(type default)
			)
			(layer "F.Fab")
		)
		(fp_line
			(start 0.67945 0.3048)
			(end 0.120396 0.3048)
			(stroke
				(width 0.1)
				(type default)
			)
			(layer "F.Fab")
		)
		(pad "1" smd circle
			(at -0.40005 0)
			(size 0 0)
			(layers "F.Cu" "F.Mask" "F.Paste")
			(net "P3V3_AUX")
		)
		(pad "2" smd circle
			(at 0.40005 0)
			(size 0 0)
			(layers "F.Cu" "F.Mask" "F.Paste")
			(net "FM_FLASH_SECURITY_STRAP")
		)
	)
	(footprint ""
		(layer "F.Cu")
		(at 108.56722 -296.05478)
		(property "Reference" "C260"
			(at 0 0 0)
			(layer "F.SilkS")
			(hide yes)
			(effects
				(font
					(size 1.27 1.27)
				)
			)
		)
		(property "Value" ""
			(at 0 0 0)
			(layer "F.Fab")
			(effects
				(font
					(size 1.27 1.27)
				)
			)
		)
		(duplicate_pad_numbers_are_jumpers no)
		(fp_line
			(start -1.524 -0.762)
			(end 1.524 -0.762)
			(stroke
				(width 0.1524)
				(type default)
			)
			(layer "F.SilkS")
		)
		(fp_line
			(start -1.524 0.762)
			(end -1.524 -0.762)
			(stroke
				(width 0.1524)
				(type default)
			)
			(layer "F.SilkS")
		)
		(fp_line
			(start 1.524 -0.762)
			(end 1.524 0.762)
			(stroke
				(width 0.1524)
				(type default)
			)
			(layer "F.SilkS")
		)
		(fp_line
			(start 1.524 0.762)
			(end -1.524 0.762)
			(stroke
				(width 0.1524)
				(type default)
			)
			(layer "F.SilkS")
		)
		(fp_line
			(start -1.1049 -0.724916)
			(end -1.1049 0.724916)
			(stroke
				(width 0.1)
				(type default)
			)
			(layer "F.Fab")
		)
		(fp_line
			(start -1.1049 0.724916)
			(end 1.1049 0.724916)
			(stroke
				(width 0.1)
				(type default)
			)
			(layer "F.Fab")
		)
		(fp_line
			(start 1.1049 -0.724916)
			(end -1.1049 -0.724916)
			(stroke
				(width 0.1)
				(type default)
			)
			(layer "F.Fab")
		)
		(fp_line
			(start 1.1049 0.724916)
			(end 1.1049 -0.724916)
			(stroke
				(width 0.1)
				(type default)
			)
			(layer "F.Fab")
		)
		(pad "1" smd rect
			(at -0.889 0 180)
			(size 1.016 1.27)
			(layers "F.Cu" "F.Mask" "F.Paste")
			(net "PVCCIN_CPU1")
		)
		(pad "2" smd rect
			(at 0.889 0 180)
			(size 1.016 1.27)
			(layers "F.Cu" "F.Mask" "F.Paste")
			(net "GND")
		)
	)
)
